(kicad_pcb
	(version 20260206)
	(generator "pcbnew")
	(generator_version "10.0")
	(general
		(thickness 1.6)
		(legacy_teardrops no)
	)
	(paper "A4")
	(title_block
		(title "04192023_DAF0TMB3IC0_F0TG_MB_C_brd_V02_OCP.brd")
		(comment 1 "Grand Teton / footprint 3955 of 8354 (U25), pads 5121-5228 of 6102")
	)
	(layers
		(0 "F.Cu" signal "TOP")
		(4 "In1.Cu" signal "GND")
		(6 "In2.Cu" signal "IN1")
		(8 "In3.Cu" signal "GND1")
		(10 "In4.Cu" signal "IN2")
		(12 "In5.Cu" signal "GND2")
		(14 "In6.Cu" signal "IN3")
		(16 "In7.Cu" signal "GND3")
		(18 "In8.Cu" signal "VCC")
		(20 "In9.Cu" signal "VCC1")
		(22 "In10.Cu" signal "GND4")
		(24 "In11.Cu" signal "IN4")
		(26 "In12.Cu" signal "GND5")
		(28 "In13.Cu" signal "IN5")
		(30 "In14.Cu" signal "GND6")
		(32 "In15.Cu" signal "IN6")
		(34 "In16.Cu" signal "GND7")
		(2 "B.Cu" signal "BOTTOM")
		(9 "F.Adhes" user "F.Adhesive")
		(11 "B.Adhes" user "B.Adhesive")
		(13 "F.Paste" user "Package Geometry/Pastemask Top")
		(15 "B.Paste" user "Package Geometry/Pastemask Bottom")
		(5 "F.SilkS" user "Ref Des/Silkscreen Top")
		(7 "B.SilkS" user "Ref Des/Silkscreen Bottom")
		(1 "F.Mask" user "Board Geometry/Soldermask Top")
		(3 "B.Mask" user "Board Geometry/Soldermask Bottom")
		(17 "Dwgs.User" user "User.Drawings")
		(19 "Cmts.User" user "User.Comments")
		(21 "Eco1.User" user "User.Eco1")
		(23 "Eco2.User" user "User.Eco2")
		(25 "Edge.Cuts" user "Board Geometry/Outline")
		(27 "Margin" user)
		(31 "F.CrtYd" user "Package Geometry/Place Bound Top")
		(29 "B.CrtYd" user "Package Geometry/Place Bound Bottom")
		(35 "F.Fab" user "Ref Des/Assembly Top")
		(33 "B.Fab" user "Ref Des/Assembly Bottom")
	)
	(footprint ""
		(layer "F.Cu")
		(at 359.867962 -258.880102 180)
		(property "Reference" "U25"
			(at -45.78477 -62.086744 0)
			(unlocked yes)
			(layer "F.SilkS")
			(effects
				(font
					(size 0.7874 0.5842)
					(thickness 0.1524)
				)
			)
		)
		(property "Value" ""
			(at 0 0 180)
			(layer "F.Fab")
			(effects
				(font
					(size 1.27 1.27)
				)
			)
		)
		(duplicate_pad_numbers_are_jumpers no)
		(pad "G27" smd circle
			(at -9.720072 -31.949898 180)
			(size 0.450088 0.450088)
			(layers "F.Cu" "F.Mask" "F.Paste")
			(net "GMI_CPU0_G2_CPU1_G0_TX_DN<5>")
		)
		(pad "G28" smd circle
			(at -8.780018 -31.949898 180)
			(size 0.450088 0.450088)
			(layers "F.Cu" "F.Mask" "F.Paste")
			(net "GND")
		)
		(pad "G29" smd circle
			(at -7.839964 -31.949898 180)
			(size 0.450088 0.450088)
			(layers "F.Cu" "F.Mask" "F.Paste")
			(net "GMI_CPU0_G2_CPU1_G0_TX_DP<8>")
		)
		(pad "G30" smd circle
			(at -6.89991 -31.949898 180)
			(size 0.450088 0.450088)
			(layers "F.Cu" "F.Mask" "F.Paste")
			(net "GMI_CPU0_G2_CPU1_G0_TX_DN<8>")
		)
		(pad "G31" smd circle
			(at -5.96011 -31.949898 180)
			(size 0.450088 0.450088)
			(layers "F.Cu" "F.Mask" "F.Paste")
			(net "GND")
		)
		(pad "G32" smd circle
			(at -5.020056 -31.949898 180)
			(size 0.450088 0.450088)
			(layers "F.Cu" "F.Mask" "F.Paste")
			(net "GMI_CPU0_G2_CPU1_G0_TX_DP<11>")
		)
		(pad "G33" smd circle
			(at -4.080002 -31.949898 180)
			(size 0.450088 0.450088)
			(layers "F.Cu" "F.Mask" "F.Paste")
			(net "GMI_CPU0_G2_CPU1_G0_TX_DN<11>")
		)
		(pad "G34" smd circle
			(at -3.139948 -31.949898 180)
			(size 0.450088 0.450088)
			(layers "F.Cu" "F.Mask" "F.Paste")
			(net "GND")
		)
		(pad "G35" smd circle
			(at -2.199894 -31.949898 180)
			(size 0.450088 0.450088)
			(layers "F.Cu" "F.Mask" "F.Paste")
			(net "PVDDCR_CPU0_P0")
		)
		(pad "G36" smd circle
			(at -1.260094 -31.949898 180)
			(size 0.450088 0.450088)
			(layers "F.Cu" "F.Mask" "F.Paste")
			(net "PVDDCR_CPU0_P0")
		)
		(pad "G40" smd circle
			(at 1.560068 -31.949898 180)
			(size 0.450088 0.450088)
			(layers "F.Cu" "F.Mask" "F.Paste")
			(net "PVDDCR_CPU0_P0")
		)
		(pad "G41" smd circle
			(at 2.500122 -31.949898 180)
			(size 0.450088 0.450088)
			(layers "F.Cu" "F.Mask" "F.Paste")
			(net "PVDDCR_CPU0_P0")
		)
		(pad "G42" smd circle
			(at 3.439922 -31.949898 180)
			(size 0.450088 0.450088)
			(layers "F.Cu" "F.Mask" "F.Paste")
			(net "GND")
		)
		(pad "G43" smd circle
			(at 4.379976 -31.949898 180)
			(size 0.450088 0.450088)
			(layers "F.Cu" "F.Mask" "F.Paste")
			(net "GMI_CPU1_G2_CPU0_G0_TX_DN<4>")
		)
		(pad "G44" smd circle
			(at 5.32003 -31.949898 180)
			(size 0.450088 0.450088)
			(layers "F.Cu" "F.Mask" "F.Paste")
			(net "GMI_CPU1_G2_CPU0_G0_TX_DP<4>")
		)
		(pad "G45" smd circle
			(at 6.260084 -31.949898 180)
			(size 0.450088 0.450088)
			(layers "F.Cu" "F.Mask" "F.Paste")
			(net "GND")
		)
		(pad "G46" smd circle
			(at 7.199884 -31.949898 180)
			(size 0.450088 0.450088)
			(layers "F.Cu" "F.Mask" "F.Paste")
			(net "GMI_CPU1_G2_CPU0_G0_TX_DN<7>")
		)
		(pad "G47" smd circle
			(at 8.139938 -31.949898 180)
			(size 0.450088 0.450088)
			(layers "F.Cu" "F.Mask" "F.Paste")
			(net "GMI_CPU1_G2_CPU0_G0_TX_DP<7>")
		)
		(pad "G48" smd circle
			(at 9.079992 -31.949898 180)
			(size 0.450088 0.450088)
			(layers "F.Cu" "F.Mask" "F.Paste")
			(net "GND")
		)
		(pad "G49" smd circle
			(at 10.020046 -31.949898 180)
			(size 0.450088 0.450088)
			(layers "F.Cu" "F.Mask" "F.Paste")
			(net "GMI_CPU1_G2_CPU0_G0_TX_DN<10>")
		)
		(pad "G50" smd circle
			(at 10.9601 -31.949898 180)
			(size 0.450088 0.450088)
			(layers "F.Cu" "F.Mask" "F.Paste")
			(net "GMI_CPU1_G2_CPU0_G0_TX_DP<10>")
		)
		(pad "G51" smd circle
			(at 11.8999 -31.949898 180)
			(size 0.450088 0.450088)
			(layers "F.Cu" "F.Mask" "F.Paste")
			(net "GND")
		)
		(pad "G52" smd circle
			(at 12.839954 -31.949898 180)
			(size 0.450088 0.450088)
			(layers "F.Cu" "F.Mask" "F.Paste")
			(net "GMI_CPU1_G2_CPU0_G0_TX_DN<13>")
		)
		(pad "G53" smd circle
			(at 13.780008 -31.949898 180)
			(size 0.450088 0.450088)
			(layers "F.Cu" "F.Mask" "F.Paste")
			(net "GMI_CPU1_G2_CPU0_G0_TX_DP<13>")
		)
		(pad "G54" smd circle
			(at 14.720062 -31.949898 180)
			(size 0.450088 0.450088)
			(layers "F.Cu" "F.Mask" "F.Paste")
			(net "GND")
		)
		(pad "G55" smd circle
			(at 15.660116 -31.949898 180)
			(size 0.450088 0.450088)
			(layers "F.Cu" "F.Mask" "F.Paste")
			(net "M_C_CPU0_SA_DQ<3>")
		)
		(pad "G56" smd circle
			(at 16.599916 -31.949898 180)
			(size 0.450088 0.450088)
			(layers "F.Cu" "F.Mask" "F.Paste")
			(net "GND")
		)
		(pad "G57" smd circle
			(at 17.53997 -31.949898 180)
			(size 0.450088 0.450088)
			(layers "F.Cu" "F.Mask" "F.Paste")
			(net "M_C_CPU0_SA_DQS_DP<0>")
		)
		(pad "G58" smd circle
			(at 18.480024 -31.949898 180)
			(size 0.450088 0.450088)
			(layers "F.Cu" "F.Mask" "F.Paste")
			(net "GND")
		)
		(pad "G59" smd circle
			(at 19.420078 -31.949898 180)
			(size 0.450088 0.450088)
			(layers "F.Cu" "F.Mask" "F.Paste")
			(net "M_D_CPU0_SA_DQ<3>")
		)
		(pad "G60" smd circle
			(at 20.359878 -31.949898 180)
			(size 0.450088 0.450088)
			(layers "F.Cu" "F.Mask" "F.Paste")
			(net "M_D_CPU0_SA_DQS_DP<0>")
		)
		(pad "G61" smd circle
			(at 21.299932 -31.949898 180)
			(size 0.450088 0.450088)
			(layers "F.Cu" "F.Mask" "F.Paste")
			(net "GND")
		)
		(pad "G62" smd circle
			(at 22.239986 -31.949898 180)
			(size 0.450088 0.450088)
			(layers "F.Cu" "F.Mask" "F.Paste")
			(net "M_B_CPU0_SA_DQ<3>")
		)
		(pad "G63" smd circle
			(at 23.18004 -31.949898 180)
			(size 0.450088 0.450088)
			(layers "F.Cu" "F.Mask" "F.Paste")
			(net "GND")
		)
		(pad "G64" smd circle
			(at 24.120094 -31.949898 180)
			(size 0.450088 0.450088)
			(layers "F.Cu" "F.Mask" "F.Paste")
			(net "M_B_CPU0_SA_DQS_DP<0>")
		)
		(pad "G65" smd circle
			(at 25.059894 -31.949898 180)
			(size 0.450088 0.450088)
			(layers "F.Cu" "F.Mask" "F.Paste")
			(net "GND")
		)
		(pad "G66" smd circle
			(at 25.999948 -31.949898 180)
			(size 0.450088 0.450088)
			(layers "F.Cu" "F.Mask" "F.Paste")
			(net "M_F_CPU0_SA_DQ<3>")
		)
		(pad "G67" smd circle
			(at 26.940002 -31.949898 180)
			(size 0.450088 0.450088)
			(layers "F.Cu" "F.Mask" "F.Paste")
			(net "M_F_CPU0_SA_DQS_DP<0>")
		)
		(pad "G68" smd circle
			(at 27.880056 -31.949898 180)
			(size 0.450088 0.450088)
			(layers "F.Cu" "F.Mask" "F.Paste")
			(net "GND")
		)
		(pad "G69" smd circle
			(at 28.82011 -31.949898 180)
			(size 0.450088 0.450088)
			(layers "F.Cu" "F.Mask" "F.Paste")
			(net "M_E_CPU0_SA_DQ<3>")
		)
		(pad "G70" smd circle
			(at 29.75991 -31.949898 180)
			(size 0.450088 0.450088)
			(layers "F.Cu" "F.Mask" "F.Paste")
			(net "GND")
		)
		(pad "G71" smd circle
			(at 30.699964 -31.949898 180)
			(size 0.450088 0.450088)
			(layers "F.Cu" "F.Mask" "F.Paste")
			(net "M_E_CPU0_SA_DQS_DP<0>")
		)
		(pad "G72" smd circle
			(at 31.640018 -31.949898 180)
			(size 0.450088 0.450088)
			(layers "F.Cu" "F.Mask" "F.Paste")
			(net "GND")
		)
		(pad "G73" smd circle
			(at 32.580072 -31.949898 180)
			(size 0.450088 0.450088)
			(layers "F.Cu" "F.Mask" "F.Paste")
			(net "M_A_CPU0_SA_DQ<3>")
		)
		(pad "G74" smd circle
			(at 33.519872 -31.949898 180)
			(size 0.450088 0.450088)
			(layers "F.Cu" "F.Mask" "F.Paste")
			(net "M_A_CPU0_SA_DQS_DP<0>")
		)
		(pad "G75" smd circle
			(at 34.459926 -31.949898 180)
			(size 0.450088 0.450088)
			(layers "F.Cu" "F.Mask" "F.Paste")
			(net "GND")
		)
		(pad "H2" smd circle
			(at -33.690052 -31.139892 180)
			(size 0.450088 0.450088)
			(layers "F.Cu" "F.Mask" "F.Paste")
			(net "M_G_CPU0_SA_DQS_DN<0>")
		)
		(pad "H3" smd circle
			(at -32.749998 -31.139892 180)
			(size 0.450088 0.450088)
			(layers "F.Cu" "F.Mask" "F.Paste")
			(net "GND")
		)
		(pad "H4" smd circle
			(at -31.809944 -31.139892 180)
			(size 0.450088 0.450088)
			(layers "F.Cu" "F.Mask" "F.Paste")
			(net "M_G_CPU0_SA_DQS_DN<5>")
		)
		(pad "H5" smd circle
			(at -30.86989 -31.139892 180)
			(size 0.450088 0.450088)
			(layers "F.Cu" "F.Mask" "F.Paste")
			(net "PVDDCR_SOC_P0")
		)
		(pad "H6" smd circle
			(at -29.93009 -31.139892 180)
			(size 0.450088 0.450088)
			(layers "F.Cu" "F.Mask" "F.Paste")
			(net "M_K_CPU0_SA_DQS_DN<0>")
		)
		(pad "H7" smd circle
			(at -28.990036 -31.139892 180)
			(size 0.450088 0.450088)
			(layers "F.Cu" "F.Mask" "F.Paste")
			(net "M_K_CPU0_SA_DQS_DN<5>")
		)
		(pad "H8" smd circle
			(at -28.049982 -31.139892 180)
			(size 0.450088 0.450088)
			(layers "F.Cu" "F.Mask" "F.Paste")
			(net "GND")
		)
		(pad "H9" smd circle
			(at -27.109928 -31.139892 180)
			(size 0.450088 0.450088)
			(layers "F.Cu" "F.Mask" "F.Paste")
			(net "M_L_CPU0_SA_DQS_DN<0>")
		)
		(pad "H10" smd circle
			(at -26.170128 -31.139892 180)
			(size 0.450088 0.450088)
			(layers "F.Cu" "F.Mask" "F.Paste")
			(net "GND")
		)
		(pad "H11" smd circle
			(at -25.230074 -31.139892 180)
			(size 0.450088 0.450088)
			(layers "F.Cu" "F.Mask" "F.Paste")
			(net "M_L_CPU0_SA_DQS_DN<5>")
		)
		(pad "H12" smd circle
			(at -24.29002 -31.139892 180)
			(size 0.450088 0.450088)
			(layers "F.Cu" "F.Mask" "F.Paste")
			(net "PVDDCR_SOC_P0")
		)
		(pad "H13" smd circle
			(at -23.349966 -31.139892 180)
			(size 0.450088 0.450088)
			(layers "F.Cu" "F.Mask" "F.Paste")
			(net "M_H_CPU0_SA_DQS_DN<0>")
		)
		(pad "H14" smd circle
			(at -22.409912 -31.139892 180)
			(size 0.450088 0.450088)
			(layers "F.Cu" "F.Mask" "F.Paste")
			(net "M_H_CPU0_SA_DQS_DN<5>")
		)
		(pad "H15" smd circle
			(at -21.470112 -31.139892 180)
			(size 0.450088 0.450088)
			(layers "F.Cu" "F.Mask" "F.Paste")
			(net "GND")
		)
		(pad "H16" smd circle
			(at -20.530058 -31.139892 180)
			(size 0.450088 0.450088)
			(layers "F.Cu" "F.Mask" "F.Paste")
			(net "M_J_CPU0_SA_DQS_DN<0>")
		)
		(pad "H17" smd circle
			(at -19.590004 -31.139892 180)
			(size 0.450088 0.450088)
			(layers "F.Cu" "F.Mask" "F.Paste")
			(net "GND")
		)
		(pad "H18" smd circle
			(at -18.64995 -31.139892 180)
			(size 0.450088 0.450088)
			(layers "F.Cu" "F.Mask" "F.Paste")
			(net "M_J_CPU0_SA_DQS_DN<5>")
		)
		(pad "H19" smd circle
			(at -17.709896 -31.139892 180)
			(size 0.450088 0.450088)
			(layers "F.Cu" "F.Mask" "F.Paste")
			(net "PVDDCR_SOC_P0")
		)
		(pad "H20" smd circle
			(at -16.770096 -31.139892 180)
			(size 0.450088 0.450088)
			(layers "F.Cu" "F.Mask" "F.Paste")
			(net "M_I_CPU0_SA_DQS_DN<0>")
		)
		(pad "H21" smd circle
			(at -15.830042 -31.139892 180)
			(size 0.450088 0.450088)
			(layers "F.Cu" "F.Mask" "F.Paste")
			(net "M_I_CPU0_SA_DQS_DN<5>")
		)
		(pad "H22" smd circle
			(at -14.889988 -31.139892 180)
			(size 0.450088 0.450088)
			(layers "F.Cu" "F.Mask" "F.Paste")
			(net "GND")
		)
		(pad "H23" smd circle
			(at -13.949934 -31.139892 180)
			(size 0.450088 0.450088)
			(layers "F.Cu" "F.Mask" "F.Paste")
			(net "PVDDCR_CPU0_P0")
		)
		(pad "H24" smd circle
			(at -13.00988 -31.139892 180)
			(size 0.450088 0.450088)
			(layers "F.Cu" "F.Mask" "F.Paste")
			(net "PVDDCR_CPU0_P0")
		)
		(pad "H25" smd circle
			(at -12.07008 -31.139892 180)
			(size 0.450088 0.450088)
			(layers "F.Cu" "F.Mask" "F.Paste")
			(net "GND")
		)
		(pad "H26" smd circle
			(at -11.130026 -31.139892 180)
			(size 0.450088 0.450088)
			(layers "F.Cu" "F.Mask" "F.Paste")
			(net "PVDDCR_CPU0_P0")
		)
		(pad "H27" smd circle
			(at -10.189972 -31.139892 180)
			(size 0.450088 0.450088)
			(layers "F.Cu" "F.Mask" "F.Paste")
			(net "PVDDCR_CPU0_P0")
		)
		(pad "H28" smd circle
			(at -9.249918 -31.139892 180)
			(size 0.450088 0.450088)
			(layers "F.Cu" "F.Mask" "F.Paste")
			(net "GND")
		)
		(pad "H29" smd circle
			(at -8.310118 -31.139892 180)
			(size 0.450088 0.450088)
			(layers "F.Cu" "F.Mask" "F.Paste")
			(net "PVDDCR_CPU0_P0")
		)
		(pad "H30" smd circle
			(at -7.370064 -31.139892 180)
			(size 0.450088 0.450088)
			(layers "F.Cu" "F.Mask" "F.Paste")
			(net "PVDDCR_CPU0_P0")
		)
		(pad "H31" smd circle
			(at -6.43001 -31.139892 180)
			(size 0.450088 0.450088)
			(layers "F.Cu" "F.Mask" "F.Paste")
			(net "GND")
		)
		(pad "H32" smd circle
			(at -5.489956 -31.139892 180)
			(size 0.450088 0.450088)
			(layers "F.Cu" "F.Mask" "F.Paste")
			(net "PVDDCR_CPU0_P0")
		)
		(pad "H33" smd circle
			(at -4.549902 -31.139892 180)
			(size 0.450088 0.450088)
			(layers "F.Cu" "F.Mask" "F.Paste")
			(net "PVDDCR_CPU0_P0")
		)
		(pad "H34" smd circle
			(at -3.610102 -31.139892 180)
			(size 0.450088 0.450088)
			(layers "F.Cu" "F.Mask" "F.Paste")
			(net "GND")
		)
		(pad "H35" smd circle
			(at -2.670048 -31.139892 180)
			(size 0.450088 0.450088)
			(layers "F.Cu" "F.Mask" "F.Paste")
			(net "GMI_CPU0_G2_CPU1_G0_TX_DP<13>")
		)
		(pad "H36" smd circle
			(at -1.729994 -31.139892 180)
			(size 0.450088 0.450088)
			(layers "F.Cu" "F.Mask" "F.Paste")
			(net "GMI_CPU0_G2_CPU1_G0_TX_DN<13>")
		)
		(pad "H37" smd circle
			(at -0.78994 -31.139892 180)
			(size 0.450088 0.450088)
			(layers "F.Cu" "F.Mask" "F.Paste")
			(net "GND")
		)
		(pad "H39" smd circle
			(at 1.089914 -31.139892 180)
			(size 0.450088 0.450088)
			(layers "F.Cu" "F.Mask" "F.Paste")
			(net "GND")
		)
		(pad "H40" smd circle
			(at 2.029968 -31.139892 180)
			(size 0.450088 0.450088)
			(layers "F.Cu" "F.Mask" "F.Paste")
			(net "GMI_CPU1_G2_CPU0_G0_TX_DN<2>")
		)
		(pad "H41" smd circle
			(at 2.970022 -31.139892 180)
			(size 0.450088 0.450088)
			(layers "F.Cu" "F.Mask" "F.Paste")
			(net "GMI_CPU1_G2_CPU0_G0_TX_DP<2>")
		)
		(pad "H42" smd circle
			(at 3.910076 -31.139892 180)
			(size 0.450088 0.450088)
			(layers "F.Cu" "F.Mask" "F.Paste")
			(net "GND")
		)
		(pad "H43" smd circle
			(at 4.849876 -31.139892 180)
			(size 0.450088 0.450088)
			(layers "F.Cu" "F.Mask" "F.Paste")
			(net "PVDDCR_CPU0_P0")
		)
		(pad "H44" smd circle
			(at 5.78993 -31.139892 180)
			(size 0.450088 0.450088)
			(layers "F.Cu" "F.Mask" "F.Paste")
			(net "PVDDCR_CPU0_P0")
		)
		(pad "H45" smd circle
			(at 6.729984 -31.139892 180)
			(size 0.450088 0.450088)
			(layers "F.Cu" "F.Mask" "F.Paste")
			(net "GND")
		)
		(pad "H46" smd circle
			(at 7.670038 -31.139892 180)
			(size 0.450088 0.450088)
			(layers "F.Cu" "F.Mask" "F.Paste")
			(net "PVDDCR_CPU0_P0")
		)
		(pad "H47" smd circle
			(at 8.610092 -31.139892 180)
			(size 0.450088 0.450088)
			(layers "F.Cu" "F.Mask" "F.Paste")
			(net "PVDDCR_CPU0_P0")
		)
		(pad "H48" smd circle
			(at 9.549892 -31.139892 180)
			(size 0.450088 0.450088)
			(layers "F.Cu" "F.Mask" "F.Paste")
			(net "GND")
		)
		(pad "H49" smd circle
			(at 10.489946 -31.139892 180)
			(size 0.450088 0.450088)
			(layers "F.Cu" "F.Mask" "F.Paste")
			(net "PVDDCR_CPU0_P0")
		)
		(pad "H50" smd circle
			(at 11.43 -31.139892 180)
			(size 0.450088 0.450088)
			(layers "F.Cu" "F.Mask" "F.Paste")
			(net "PVDDCR_CPU0_P0")
		)
		(pad "H51" smd circle
			(at 12.370054 -31.139892 180)
			(size 0.450088 0.450088)
			(layers "F.Cu" "F.Mask" "F.Paste")
			(net "GND")
		)
		(pad "H52" smd circle
			(at 13.310108 -31.139892 180)
			(size 0.450088 0.450088)
			(layers "F.Cu" "F.Mask" "F.Paste")
			(net "PVDDCR_CPU0_P0")
		)
		(pad "H53" smd circle
			(at 14.249908 -31.139892 180)
			(size 0.450088 0.450088)
			(layers "F.Cu" "F.Mask" "F.Paste")
			(net "PVDDCR_CPU0_P0")
		)
		(pad "H54" smd circle
			(at 15.189962 -31.139892 180)
			(size 0.450088 0.450088)
			(layers "F.Cu" "F.Mask" "F.Paste")
			(net "GND")
		)
		(pad "H55" smd circle
			(at 16.130016 -31.139892 180)
			(size 0.450088 0.450088)
			(layers "F.Cu" "F.Mask" "F.Paste")
			(net "M_C_CPU0_SA_DQS_DN<5>")
		)
		(pad "H56" smd circle
			(at 17.07007 -31.139892 180)
			(size 0.450088 0.450088)
			(layers "F.Cu" "F.Mask" "F.Paste")
			(net "M_C_CPU0_SA_DQS_DN<0>")
		)
		(pad "H57" smd circle
			(at 18.010124 -31.139892 180)
			(size 0.450088 0.450088)
			(layers "F.Cu" "F.Mask" "F.Paste")
			(net "PVDDIO_P0")
		)
		(pad "H58" smd circle
			(at 18.949924 -31.139892 180)
			(size 0.450088 0.450088)
			(layers "F.Cu" "F.Mask" "F.Paste")
			(net "M_D_CPU0_SA_DQS_DN<5>")
		)
		(pad "H59" smd circle
			(at 19.889978 -31.139892 180)
			(size 0.450088 0.450088)
			(layers "F.Cu" "F.Mask" "F.Paste")
			(net "GND")
		)
		(pad "H60" smd circle
			(at 20.830032 -31.139892 180)
			(size 0.450088 0.450088)
			(layers "F.Cu" "F.Mask" "F.Paste")
			(net "M_D_CPU0_SA_DQS_DN<0>")
		)
		(pad "H61" smd circle
			(at 21.770086 -31.139892 180)
			(size 0.450088 0.450088)
			(layers "F.Cu" "F.Mask" "F.Paste")
			(net "GND")
		)
		(pad "H62" smd circle
			(at 22.709886 -31.139892 180)
			(size 0.450088 0.450088)
			(layers "F.Cu" "F.Mask" "F.Paste")
			(net "M_B_CPU0_SA_DQS_DN<5>")
		)
		(pad "H63" smd circle
			(at 23.64994 -31.139892 180)
			(size 0.450088 0.450088)
			(layers "F.Cu" "F.Mask" "F.Paste")
			(net "M_B_CPU0_SA_DQS_DN<0>")
		)
		(pad "H64" smd circle
			(at 24.589994 -31.139892 180)
			(size 0.450088 0.450088)
			(layers "F.Cu" "F.Mask" "F.Paste")
			(net "PVDDIO_P0")
		)
	)
)
